# S9S_MB_2U (Grand Teton) — schematic netlist excerpt (pin names and nets, part order shuffled) for the footprints in the layout excerpt that follows; sources: Cadence DE-HDL packaged netlist, KiCad conversion of 03242023_DA0F0TMBIJ0_F0T_Motherboard_J_brd_V01_OCP.brd

C1026  Q_CAP  22UF 4V 20% X6S  pkg C0402  page 74 : A = PVCCIN_CPU0 ; B = GND
C605  Q_CAP  1UF 25V 10% X6S  pkg C0402  page 202 : A = PGPPA_AUX ; B = GND

(kicad_pcb
	(version 20260206)
	(generator "pcbnew")
	(generator_version "10.0")
	(general
		(thickness 1.6)
		(legacy_teardrops no)
	)
	(paper "A4")
	(title_block
		(title "03242023_DA0F0TMBIJ0_F0T_Motherboard_J_brd_V01_OCP.brd")
		(comment 1 "Grand Teton / footprints 3055-3056 of 6105")
	)
	(layers
		(0 "F.Cu" signal "TOP")
		(4 "In1.Cu" signal "GND")
		(6 "In2.Cu" signal "IN1")
		(8 "In3.Cu" signal "GND1")
		(10 "In4.Cu" signal "IN2")
		(12 "In5.Cu" signal "GND2")
		(14 "In6.Cu" signal "IN3")
		(16 "In7.Cu" signal "GND3")
		(18 "In8.Cu" signal "VCC")
		(20 "In9.Cu" signal "VCC1")
		(22 "In10.Cu" signal "GND4")
		(24 "In11.Cu" signal "IN4")
		(26 "In12.Cu" signal "GND5")
		(28 "In13.Cu" signal "IN5")
		(30 "In14.Cu" signal "GND6")
		(32 "In15.Cu" signal "IN6")
		(34 "In16.Cu" signal "GND7")
		(2 "B.Cu" signal "BOTTOM")
		(9 "F.Adhes" user "F.Adhesive")
		(11 "B.Adhes" user "B.Adhesive")
		(13 "F.Paste" user "Package Geometry/Pastemask Top")
		(15 "B.Paste" user "Package Geometry/Pastemask Bottom")
		(5 "F.SilkS" user "Ref Des/Silkscreen Top")
		(7 "B.SilkS" user "Ref Des/Silkscreen Bottom")
		(1 "F.Mask" user "Board Geometry/Soldermask Top")
		(3 "B.Mask" user "Board Geometry/Soldermask Bottom")
		(17 "Dwgs.User" user "User.Drawings")
		(19 "Cmts.User" user "User.Comments")
		(21 "Eco1.User" user "User.Eco1")
		(23 "Eco2.User" user "User.Eco2")
		(25 "Edge.Cuts" user "Board Geometry/Outline")
		(27 "Margin" user)
		(31 "F.CrtYd" user "Package Geometry/Place Bound Top")
		(29 "B.CrtYd" user "Package Geometry/Place Bound Bottom")
		(35 "F.Fab" user "Ref Des/Assembly Top")
		(33 "B.Fab" user "Ref Des/Assembly Bottom")
	)
	(footprint ""
		(layer "F.Cu")
		(at 337.845908 -16.219678 -90)
		(property "Reference" "C605"
			(at 0 0 270)
			(layer "F.SilkS")
			(hide yes)
			(effects
				(font
					(size 1.27 1.27)
				)
			)
		)
		(property "Value" ""
			(at 0 0 270)
			(layer "F.Fab")
			(effects
				(font
					(size 1.27 1.27)
				)
			)
		)
		(duplicate_pad_numbers_are_jumpers no)
		(fp_line
			(start -0.7874 0.4064)
			(end -0.7874 -0.4064)
			(stroke
				(width 0.1524)
				(type default)
			)
			(layer "F.SilkS")
		)
		(fp_line
			(start 0.7874 0.4064)
			(end -0.7874 0.4064)
			(stroke
				(width 0.1524)
				(type default)
			)
			(layer "F.SilkS")
		)
		(fp_line
			(start -0.7874 -0.4064)
			(end 0.7874 -0.4064)
			(stroke
				(width 0.1524)
				(type default)
			)
			(layer "F.SilkS")
		)
		(fp_line
			(start 0.7874 -0.4064)
			(end 0.7874 0.4064)
			(stroke
				(width 0.1524)
				(type default)
			)
			(layer "F.SilkS")
		)
		(fp_line
			(start -0.67945 0.3048)
			(end -0.67945 -0.305054)
			(stroke
				(width 0.1)
				(type default)
			)
			(layer "F.Fab")
		)
		(fp_line
			(start -0.12065 0.3048)
			(end -0.67945 0.3048)
			(stroke
				(width 0.1)
				(type default)
			)
			(layer "F.Fab")
		)
		(fp_line
			(start 0.120396 0.3048)
			(end 0.120396 0.2794)
			(stroke
				(width 0.1)
				(type default)
			)
			(layer "F.Fab")
		)
		(fp_line
			(start 0.67945 0.3048)
			(end 0.120396 0.3048)
			(stroke
				(width 0.1)
				(type default)
			)
			(layer "F.Fab")
		)
		(fp_line
			(start -0.12065 0.2794)
			(end -0.12065 0.3048)
			(stroke
				(width 0.1)
				(type default)
			)
			(layer "F.Fab")
		)
		(fp_line
			(start 0.120396 0.2794)
			(end -0.12065 0.2794)
			(stroke
				(width 0.1)
				(type default)
			)
			(layer "F.Fab")
		)
		(fp_line
			(start -0.12065 -0.2794)
			(end 0.12065 -0.2794)
			(stroke
				(width 0.1)
				(type default)
			)
			(layer "F.Fab")
		)
		(fp_line
			(start 0.12065 -0.2794)
			(end 0.12065 -0.3048)
			(stroke
				(width 0.1)
				(type default)
			)
			(layer "F.Fab")
		)
		(fp_line
			(start 0.12065 -0.3048)
			(end 0.67945 -0.3048)
			(stroke
				(width 0.1)
				(type default)
			)
			(layer "F.Fab")
		)
		(fp_line
			(start 0.67945 -0.3048)
			(end 0.67945 0.3048)
			(stroke
				(width 0.1)
				(type default)
			)
			(layer "F.Fab")
		)
		(fp_line
			(start -0.67945 -0.305054)
			(end -0.12065 -0.305054)
			(stroke
				(width 0.1)
				(type default)
			)
			(layer "F.Fab")
		)
		(fp_line
			(start -0.12065 -0.305054)
			(end -0.12065 -0.2794)
			(stroke
				(width 0.1)
				(type default)
			)
			(layer "F.Fab")
		)
		(pad "1" smd circle
			(at -0.40005 0 270)
			(size 0 0)
			(layers "F.Cu" "F.Mask" "F.Paste")
			(net "PGPPA_AUX")
		)
		(pad "2" smd circle
			(at 0.40005 0 270)
			(size 0 0)
			(layers "F.Cu" "F.Mask" "F.Paste")
			(net "GND")
		)
	)
	(footprint ""
		(layer "F.Cu")
		(at 355.229414 -251.375418 90)
		(property "Reference" "C1026"
			(at 0 0 90)
			(layer "F.SilkS")
			(hide yes)
			(effects
				(font
					(size 1.27 1.27)
				)
			)
		)
		(property "Value" ""
			(at 0 0 90)
			(layer "F.Fab")
			(effects
				(font
					(size 1.27 1.27)
				)
			)
		)
		(duplicate_pad_numbers_are_jumpers no)
		(fp_line
			(start 0.7874 -0.4064)
			(end 0.7874 0.4064)
			(stroke
				(width 0.1524)
				(type default)
			)
			(layer "F.SilkS")
		)
		(fp_line
			(start -0.7874 -0.4064)
			(end 0.7874 -0.4064)
			(stroke
				(width 0.1524)
				(type default)
			)
			(layer "F.SilkS")
		)
		(fp_line
			(start 0.7874 0.4064)
			(end -0.7874 0.4064)
			(stroke
				(width 0.1524)
				(type default)
			)
			(layer "F.SilkS")
		)
		(fp_line
			(start -0.7874 0.4064)
			(end -0.7874 -0.4064)
			(stroke
				(width 0.1524)
				(type default)
			)
			(layer "F.SilkS")
		)
		(fp_line
			(start -0.12065 -0.305054)
			(end -0.12065 -0.2794)
			(stroke
				(width 0.1)
				(type default)
			)
			(layer "F.Fab")
		)
		(fp_line
			(start -0.67945 -0.305054)
			(end -0.12065 -0.305054)
			(stroke
				(width 0.1)
				(type default)
			)
			(layer "F.Fab")
		)
		(fp_line
			(start 0.67945 -0.3048)
			(end 0.67945 0.3048)
			(stroke
				(width 0.1)
				(type default)
			)
			(layer "F.Fab")
		)
		(fp_line
			(start 0.12065 -0.3048)
			(end 0.67945 -0.3048)
			(stroke
				(width 0.1)
				(type default)
			)
			(layer "F.Fab")
		)
		(fp_line
			(start 0.12065 -0.2794)
			(end 0.12065 -0.3048)
			(stroke
				(width 0.1)
				(type default)
			)
			(layer "F.Fab")
		)
		(fp_line
			(start -0.12065 -0.2794)
			(end 0.12065 -0.2794)
			(stroke
				(width 0.1)
				(type default)
			)
			(layer "F.Fab")
		)
		(fp_line
			(start 0.120396 0.2794)
			(end -0.12065 0.2794)
			(stroke
				(width 0.1)
				(type default)
			)
			(layer "F.Fab")
		)
		(fp_line
			(start -0.12065 0.2794)
			(end -0.12065 0.3048)
			(stroke
				(width 0.1)
				(type default)
			)
			(layer "F.Fab")
		)
		(fp_line
			(start 0.67945 0.3048)
			(end 0.120396 0.3048)
			(stroke
				(width 0.1)
				(type default)
			)
			(layer "F.Fab")
		)
		(fp_line
			(start 0.120396 0.3048)
			(end 0.120396 0.2794)
			(stroke
				(width 0.1)
				(type default)
			)
			(layer "F.Fab")
		)
		(fp_line
			(start -0.12065 0.3048)
			(end -0.67945 0.3048)
			(stroke
				(width 0.1)
				(type default)
			)
			(layer "F.Fab")
		)
		(fp_line
			(start -0.67945 0.3048)
			(end -0.67945 -0.305054)
			(stroke
				(width 0.1)
				(type default)
			)
			(layer "F.Fab")
		)
		(pad "1" smd circle
			(at -0.40005 0 90)
			(size 0 0)
			(layers "F.Cu" "F.Mask" "F.Paste")
			(net "PVCCIN_CPU0")
		)
		(pad "2" smd circle
			(at 0.40005 0 90)
			(size 0 0)
			(layers "F.Cu" "F.Mask" "F.Paste")
			(net "GND")
		)
	)
)
